# S9S_MB_2U (Grand Teton) — schematic netlist excerpt (pin names and nets, part order shuffled) for the footprints in the layout excerpt that follows; sources: Cadence DE-HDL packaged netlist, KiCad conversion of 03242023_DA0F0TMBIJ0_F0T_Motherboard_J_brd_V01_OCP.brd

D82  Q_LED  IC  pkg SMLF  page 254 : A = LED_PWRGD_PVCCFA_EHV_CPU1 ; C = LED_PWRGD_PVCCFA_EHV_CPU1_D
R698  Q_RES  49.9 1% CHIP  pkg 0402LF  page 205 : A = FM_ADR_TRIGGER_R_N ; B = FM_ADR_TRIGGER_N

(kicad_pcb
	(version 20260206)
	(generator "pcbnew")
	(generator_version "10.0")
	(general
		(thickness 1.6)
		(legacy_teardrops no)
	)
	(paper "A4")
	(title_block
		(title "03242023_DA0F0TMBIJ0_F0T_Motherboard_J_brd_V01_OCP.brd")
		(comment 1 "Grand Teton / footprints 2596-2597 of 6105")
	)
	(layers
		(0 "F.Cu" signal "TOP")
		(4 "In1.Cu" signal "GND")
		(6 "In2.Cu" signal "IN1")
		(8 "In3.Cu" signal "GND1")
		(10 "In4.Cu" signal "IN2")
		(12 "In5.Cu" signal "GND2")
		(14 "In6.Cu" signal "IN3")
		(16 "In7.Cu" signal "GND3")
		(18 "In8.Cu" signal "VCC")
		(20 "In9.Cu" signal "VCC1")
		(22 "In10.Cu" signal "GND4")
		(24 "In11.Cu" signal "IN4")
		(26 "In12.Cu" signal "GND5")
		(28 "In13.Cu" signal "IN5")
		(30 "In14.Cu" signal "GND6")
		(32 "In15.Cu" signal "IN6")
		(34 "In16.Cu" signal "GND7")
		(2 "B.Cu" signal "BOTTOM")
		(9 "F.Adhes" user "F.Adhesive")
		(11 "B.Adhes" user "B.Adhesive")
		(13 "F.Paste" user "Package Geometry/Pastemask Top")
		(15 "B.Paste" user "Package Geometry/Pastemask Bottom")
		(5 "F.SilkS" user "Ref Des/Silkscreen Top")
		(7 "B.SilkS" user "Ref Des/Silkscreen Bottom")
		(1 "F.Mask" user "Board Geometry/Soldermask Top")
		(3 "B.Mask" user "Board Geometry/Soldermask Bottom")
		(17 "Dwgs.User" user "User.Drawings")
		(19 "Cmts.User" user "User.Comments")
		(21 "Eco1.User" user "User.Eco1")
		(23 "Eco2.User" user "User.Eco2")
		(25 "Edge.Cuts" user "Board Geometry/Outline")
		(27 "Margin" user)
		(31 "F.CrtYd" user "Package Geometry/Place Bound Top")
		(29 "B.CrtYd" user "Package Geometry/Place Bound Bottom")
		(35 "F.Fab" user "Ref Des/Assembly Top")
		(33 "B.Fab" user "Ref Des/Assembly Bottom")
	)
	(footprint ""
		(layer "F.Cu")
		(at 312.443622 -45.202348 180)
		(property "Reference" "R698"
			(at 0 0 180)
			(layer "F.SilkS")
			(hide yes)
			(effects
				(font
					(size 1.27 1.27)
				)
			)
		)
		(property "Value" ""
			(at 0 0 180)
			(layer "F.Fab")
			(effects
				(font
					(size 1.27 1.27)
				)
			)
		)
		(duplicate_pad_numbers_are_jumpers no)
		(fp_line
			(start 0.7874 0.4064)
			(end -0.7874 0.4064)
			(stroke
				(width 0.1524)
				(type default)
			)
			(layer "F.SilkS")
		)
		(fp_line
			(start 0.7874 -0.4064)
			(end 0.7874 0.4064)
			(stroke
				(width 0.1524)
				(type default)
			)
			(layer "F.SilkS")
		)
		(fp_line
			(start -0.7874 0.4064)
			(end -0.7874 -0.4064)
			(stroke
				(width 0.1524)
				(type default)
			)
			(layer "F.SilkS")
		)
		(fp_line
			(start -0.7874 -0.4064)
			(end 0.7874 -0.4064)
			(stroke
				(width 0.1524)
				(type default)
			)
			(layer "F.SilkS")
		)
		(fp_line
			(start 0.67945 0.3048)
			(end 0.120396 0.3048)
			(stroke
				(width 0.1)
				(type default)
			)
			(layer "F.Fab")
		)
		(fp_line
			(start 0.67945 -0.3048)
			(end 0.67945 0.3048)
			(stroke
				(width 0.1)
				(type default)
			)
			(layer "F.Fab")
		)
		(fp_line
			(start 0.12065 -0.2794)
			(end 0.12065 -0.3048)
			(stroke
				(width 0.1)
				(type default)
			)
			(layer "F.Fab")
		)
		(fp_line
			(start 0.12065 -0.3048)
			(end 0.67945 -0.3048)
			(stroke
				(width 0.1)
				(type default)
			)
			(layer "F.Fab")
		)
		(fp_line
			(start 0.120396 0.3048)
			(end 0.120396 0.2794)
			(stroke
				(width 0.1)
				(type default)
			)
			(layer "F.Fab")
		)
		(fp_line
			(start 0.120396 0.2794)
			(end -0.12065 0.2794)
			(stroke
				(width 0.1)
				(type default)
			)
			(layer "F.Fab")
		)
		(fp_line
			(start -0.12065 0.3048)
			(end -0.67945 0.3048)
			(stroke
				(width 0.1)
				(type default)
			)
			(layer "F.Fab")
		)
		(fp_line
			(start -0.12065 0.2794)
			(end -0.12065 0.3048)
			(stroke
				(width 0.1)
				(type default)
			)
			(layer "F.Fab")
		)
		(fp_line
			(start -0.12065 -0.2794)
			(end 0.12065 -0.2794)
			(stroke
				(width 0.1)
				(type default)
			)
			(layer "F.Fab")
		)
		(fp_line
			(start -0.12065 -0.305054)
			(end -0.12065 -0.2794)
			(stroke
				(width 0.1)
				(type default)
			)
			(layer "F.Fab")
		)
		(fp_line
			(start -0.67945 0.3048)
			(end -0.67945 -0.305054)
			(stroke
				(width 0.1)
				(type default)
			)
			(layer "F.Fab")
		)
		(fp_line
			(start -0.67945 -0.305054)
			(end -0.12065 -0.305054)
			(stroke
				(width 0.1)
				(type default)
			)
			(layer "F.Fab")
		)
		(pad "1" smd circle
			(at -0.40005 0 180)
			(size 0 0)
			(layers "F.Cu" "F.Mask" "F.Paste")
			(net "FM_ADR_TRIGGER_R_N")
		)
		(pad "2" smd circle
			(at 0.40005 0 180)
			(size 0 0)
			(layers "F.Cu" "F.Mask" "F.Paste")
			(net "FM_ADR_TRIGGER_N")
		)
	)
	(footprint ""
		(layer "F.Cu")
		(at 67.994276 -79.078836)
		(property "Reference" "D82"
			(at -35.91941 34.331402 90)
			(unlocked yes)
			(layer "F.SilkS")
			(effects
				(font
					(size 0.635 0.4064)
					(thickness 0.1524)
				)
				(justify left)
			)
		)
		(property "Value" ""
			(at 0 0 0)
			(layer "F.Fab")
			(effects
				(font
					(size 1.27 1.27)
				)
			)
		)
		(duplicate_pad_numbers_are_jumpers no)
		(fp_line
			(start -0.90678 0.4826)
			(end -0.90678 -0.4699)
			(stroke
				(width 0.1524)
				(type default)
			)
			(layer "F.SilkS")
		)
		(fp_line
			(start -0.89408 -0.4826)
			(end 0.90678 -0.4826)
			(stroke
				(width 0.1524)
				(type default)
			)
			(layer "F.SilkS")
		)
		(fp_line
			(start -0.79248 -0.4826)
			(end 1.03378 -0.4826)
			(stroke
				(width 0.1524)
				(type default)
			)
			(layer "F.SilkS")
		)
		(fp_line
			(start -0.64008 -0.4826)
			(end 1.16078 -0.4826)
			(stroke
				(width 0.1524)
				(type default)
			)
			(layer "F.SilkS")
		)
		(fp_line
			(start 0.90678 -0.4826)
			(end 0.90678 0.4826)
			(stroke
				(width 0.1524)
				(type default)
			)
			(layer "F.SilkS")
		)
		(fp_line
			(start 0.90678 0.4826)
			(end -0.90678 0.4826)
			(stroke
				(width 0.1524)
				(type default)
			)
			(layer "F.SilkS")
		)
		(fp_line
			(start 1.03378 -0.4826)
			(end 1.03378 0.4826)
			(stroke
				(width 0.1524)
				(type default)
			)
			(layer "F.SilkS")
		)
		(fp_line
			(start 1.03378 0.4826)
			(end -0.79248 0.4826)
			(stroke
				(width 0.1524)
				(type default)
			)
			(layer "F.SilkS")
		)
		(fp_line
			(start 1.16078 -0.4826)
			(end 1.16078 0.4826)
			(stroke
				(width 0.1524)
				(type default)
			)
			(layer "F.SilkS")
		)
		(fp_line
			(start 1.16078 0.4826)
			(end -0.64008 0.4826)
			(stroke
				(width 0.1524)
				(type default)
			)
			(layer "F.SilkS")
		)
		(fp_line
			(start -0.499872 -0.249936)
			(end 0.499872 -0.249936)
			(stroke
				(width 0.1)
				(type default)
			)
			(layer "F.Fab")
		)
		(fp_line
			(start -0.499872 0.249936)
			(end -0.499872 -0.249936)
			(stroke
				(width 0.1)
				(type default)
			)
			(layer "F.Fab")
		)
		(fp_line
			(start 0.499872 -0.249936)
			(end 0.499872 0.249936)
			(stroke
				(width 0.1)
				(type default)
			)
			(layer "F.Fab")
		)
		(fp_line
			(start 0.499872 0.249936)
			(end -0.499872 0.249936)
			(stroke
				(width 0.1)
				(type default)
			)
			(layer "F.Fab")
		)
		(pad "A" smd rect
			(at -0.47498 0)
			(size 0.6096 0.7112)
			(layers "F.Cu" "F.Mask" "F.Paste")
			(net "LED_PWRGD_PVCCFA_EHV_CPU1")
		)
		(pad "C" smd rect
			(at 0.47498 0)
			(size 0.6096 0.7112)
			(layers "F.Cu" "F.Mask" "F.Paste")
			(net "LED_PWRGD_PVCCFA_EHV_CPU1_D")
		)
	)
)
